# BASEBOARD_FAB2 (Tioga Pass) — schematic netlist excerpt (pin names and nets, part order shuffled) for the footprints in the layout excerpt that follows; sources: Cadence DE-HDL packaged netlist, KiCad conversion of Wiwynn_Tioga_Pass_MB.brd

R6N12  RES  0.0 5% CHIP  pkg 0402  page 21 : A = SVID_CLK0_CPU0 ; B = SVID_CLK0_CPU0_R
C8L9  CAP_A  47UF 4V 20% X5R  pkg 0603V  page 228 : A = PVDDQ_KLM ; B = GND
R3U1  RES  33.2 1% CHIP  pkg 0402  page 153 : A = SPI_BIOS_SOCKET_IO2 ; B = PU_BIOS_SPI_WP1_N

(kicad_pcb
	(version 20260206)
	(generator "pcbnew")
	(generator_version "10.0")
	(general
		(thickness 1.6)
		(legacy_teardrops no)
	)
	(paper "A4")
	(title_block
		(title "Wiwynn_Tioga_Pass_MB.brd")
		(comment 1 "Tioga Pass / footprints 2405-2407 of 4770")
	)
	(layers
		(0 "F.Cu" signal "TOP")
		(4 "In1.Cu" signal "L2GND")
		(6 "In2.Cu" signal "L3")
		(8 "In3.Cu" signal "L4GND")
		(10 "In4.Cu" signal "L5")
		(12 "In5.Cu" signal "L6GND")
		(14 "In6.Cu" signal "L7VCC")
		(16 "In7.Cu" signal "L8VCC")
		(18 "In8.Cu" signal "L9GND")
		(20 "In9.Cu" signal "L10")
		(22 "In10.Cu" signal "L11GND")
		(24 "In11.Cu" signal "L12")
		(26 "In12.Cu" signal "L13GND")
		(2 "B.Cu" signal "BOTTOM")
		(9 "F.Adhes" user "F.Adhesive")
		(11 "B.Adhes" user "B.Adhesive")
		(13 "F.Paste" user "Package Geometry/Pastemask Top")
		(15 "B.Paste" user "Package Geometry/Pastemask Bottom")
		(5 "F.SilkS" user "Ref Des/Silkscreen Top")
		(7 "B.SilkS" user "Ref Des/Silkscreen Bottom")
		(1 "F.Mask" user "Board Geometry/Soldermask Top")
		(3 "B.Mask" user "Board Geometry/Soldermask Bottom")
		(17 "Dwgs.User" user "User.Drawings")
		(19 "Cmts.User" user "User.Comments")
		(21 "Eco1.User" user "User.Eco1")
		(23 "Eco2.User" user "User.Eco2")
		(25 "Edge.Cuts" user "Board Geometry/Outline")
		(27 "Margin" user)
		(31 "F.CrtYd" user "Package Geometry/Place Bound Top")
		(29 "B.CrtYd" user "Package Geometry/Place Bound Bottom")
		(35 "F.Fab" user "Ref Des/Assembly Top")
		(33 "B.Fab" user "Ref Des/Assembly Bottom")
	)
	(footprint ""
		(layer "B.Cu")
		(at 385.572 -49.403 90)
		(property "Reference" "R3U1"
			(at 0 0 90)
			(layer "B.SilkS")
			(hide yes)
			(effects
				(font
					(size 1.27 1.27)
				)
				(justify mirror)
			)
		)
		(property "Value" ""
			(at 0 0 90)
			(layer "B.Fab")
			(effects
				(font
					(size 1.27 1.27)
				)
				(justify mirror)
			)
		)
		(duplicate_pad_numbers_are_jumpers no)
		(fp_poly
			(pts
				(xy 0.2794 -0.1016) (xy -0.2794 -0.1016) (xy -0.2794 0.9906) (xy 0.2794 0.9906)
			)
			(stroke
				(width 0)
				(type default)
			)
			(fill no)
			(layer "B.CrtYd")
		)
		(fp_line
			(start 0.2794 -0.1016)
			(end 0.2794 0.9906)
			(stroke
				(width 0.1)
				(type default)
			)
			(layer "B.Fab")
		)
		(fp_line
			(start -0.2794 -0.1016)
			(end 0.2794 -0.1016)
			(stroke
				(width 0.1)
				(type default)
			)
			(layer "B.Fab")
		)
		(fp_line
			(start 0.2794 0.9906)
			(end -0.2794 0.9906)
			(stroke
				(width 0.1)
				(type default)
			)
			(layer "B.Fab")
		)
		(fp_line
			(start -0.2794 0.9906)
			(end -0.2794 -0.1016)
			(stroke
				(width 0.1)
				(type default)
			)
			(layer "B.Fab")
		)
		(pad "1" smd rect
			(at 0 0 270)
			(size 0.508 0.508)
			(layers "B.Cu" "B.Mask" "B.Paste")
			(net "SPI_BIOS_SOCKET_IO2")
		)
		(pad "2" smd rect
			(at 0 0.889 270)
			(size 0.508 0.508)
			(layers "B.Cu" "B.Mask" "B.Paste")
			(net "PU_BIOS_SPI_WP1_N")
		)
		(zone
			(layer "B.Cu")
			(hatch none 0.5)
			(connect_pads
				(clearance 0)
			)
			(min_thickness 0.25)
			(keepout
				(tracks allowed)
				(vias not_allowed)
				(pads allowed)
				(copperpour not_allowed)
				(footprints allowed)
			)
			(placement
				(enabled no)
				(sheetname "")
			)
			(fill
				(thermal_gap 0.5)
				(thermal_bridge_width 0.5)
				(island_removal_mode 0)
			)
			(polygon
				(pts
					(xy 385.826 -49.657) (xy 385.826 -49.149) (xy 386.207 -49.149) (xy 386.207 -49.657)
				)
			)
		)
		(zone
			(layer "B.Cu")
			(hatch none 0.5)
			(connect_pads
				(clearance 0)
			)
			(min_thickness 0.25)
			(keepout
				(tracks not_allowed)
				(vias allowed)
				(pads allowed)
				(copperpour not_allowed)
				(footprints allowed)
			)
			(placement
				(enabled no)
				(sheetname "")
			)
			(fill
				(thermal_gap 0.5)
				(thermal_bridge_width 0.5)
				(island_removal_mode 0)
			)
			(polygon
				(pts
					(xy 386.207 -49.657) (xy 386.207 -49.149) (xy 385.826 -49.149) (xy 385.826 -49.657)
				)
			)
		)
	)
	(footprint ""
		(layer "B.Cu")
		(at 205.74 -104.775 -90)
		(property "Reference" "R6N12"
			(at 0 0 90)
			(layer "B.SilkS")
			(hide yes)
			(effects
				(font
					(size 1.27 1.27)
				)
				(justify mirror)
			)
		)
		(property "Value" ""
			(at 0 0 90)
			(layer "B.Fab")
			(effects
				(font
					(size 1.27 1.27)
				)
				(justify mirror)
			)
		)
		(duplicate_pad_numbers_are_jumpers no)
		(fp_poly
			(pts
				(xy 0.2794 -0.1016) (xy -0.2794 -0.1016) (xy -0.2794 0.9906) (xy 0.2794 0.9906)
			)
			(stroke
				(width 0)
				(type default)
			)
			(fill no)
			(layer "B.CrtYd")
		)
		(fp_line
			(start -0.2794 0.9906)
			(end -0.2794 -0.1016)
			(stroke
				(width 0.1)
				(type default)
			)
			(layer "B.Fab")
		)
		(fp_line
			(start 0.2794 0.9906)
			(end -0.2794 0.9906)
			(stroke
				(width 0.1)
				(type default)
			)
			(layer "B.Fab")
		)
		(fp_line
			(start -0.2794 -0.1016)
			(end 0.2794 -0.1016)
			(stroke
				(width 0.1)
				(type default)
			)
			(layer "B.Fab")
		)
		(fp_line
			(start 0.2794 -0.1016)
			(end 0.2794 0.9906)
			(stroke
				(width 0.1)
				(type default)
			)
			(layer "B.Fab")
		)
		(pad "1" smd rect
			(at 0 0 90)
			(size 0.508 0.508)
			(layers "B.Cu" "B.Mask" "B.Paste")
			(net "SVID_CLK0_CPU0")
		)
		(pad "2" smd rect
			(at 0 0.889 90)
			(size 0.508 0.508)
			(layers "B.Cu" "B.Mask" "B.Paste")
			(net "SVID_CLK0_CPU0_R")
		)
		(zone
			(layer "B.Cu")
			(hatch none 0.5)
			(connect_pads
				(clearance 0)
			)
			(min_thickness 0.25)
			(keepout
				(tracks not_allowed)
				(vias allowed)
				(pads allowed)
				(copperpour not_allowed)
				(footprints allowed)
			)
			(placement
				(enabled no)
				(sheetname "")
			)
			(fill
				(thermal_gap 0.5)
				(thermal_bridge_width 0.5)
				(island_removal_mode 0)
			)
			(polygon
				(pts
					(xy 205.105 -104.521) (xy 205.105 -105.029) (xy 205.486 -105.029) (xy 205.486 -104.521)
				)
			)
		)
		(zone
			(layer "B.Cu")
			(hatch none 0.5)
			(connect_pads
				(clearance 0)
			)
			(min_thickness 0.25)
			(keepout
				(tracks allowed)
				(vias not_allowed)
				(pads allowed)
				(copperpour not_allowed)
				(footprints allowed)
			)
			(placement
				(enabled no)
				(sheetname "")
			)
			(fill
				(thermal_gap 0.5)
				(thermal_bridge_width 0.5)
				(island_removal_mode 0)
			)
			(polygon
				(pts
					(xy 205.486 -104.521) (xy 205.486 -105.029) (xy 205.105 -105.029) (xy 205.105 -104.521)
				)
			)
		)
	)
	(footprint ""
		(layer "B.Cu")
		(at 83.856068 -145.0086 -90)
		(property "Reference" "C8L9"
			(at -1.848866 0.752348 270)
			(unlocked yes)
			(layer "B.SilkS")
			(effects
				(font
					(size 1.27 0.9652)
					(thickness 0.1524)
				)
				(justify mirror)
			)
		)
		(property "Value" ""
			(at 0 0 90)
			(layer "B.Fab")
			(effects
				(font
					(size 1.27 1.27)
				)
				(justify mirror)
			)
		)
		(duplicate_pad_numbers_are_jumpers no)
		(fp_rect
			(start 0.500126 1.598422)
			(end -0.500126 -0.201422)
			(stroke
				(width 0)
				(type default)
			)
			(fill no)
			(layer "B.CrtYd")
		)
		(fp_line
			(start -0.500126 1.598422)
			(end 0.500126 1.598422)
			(stroke
				(width 0.1)
				(type default)
			)
			(layer "B.Fab")
		)
		(fp_line
			(start 0.500126 1.598422)
			(end 0.500126 -0.201422)
			(stroke
				(width 0.1)
				(type default)
			)
			(layer "B.Fab")
		)
		(fp_line
			(start -0.500126 -0.201422)
			(end -0.500126 1.598422)
			(stroke
				(width 0.1)
				(type default)
			)
			(layer "B.Fab")
		)
		(fp_line
			(start 0.500126 -0.201422)
			(end -0.500126 -0.201422)
			(stroke
				(width 0.1)
				(type default)
			)
			(layer "B.Fab")
		)
		(pad "1" smd rect
			(at 0 0 180)
			(size 0.889 0.9906)
			(layers "B.Cu" "B.Mask" "B.Paste")
			(net "PVDDQ_KLM")
		)
		(pad "2" smd rect
			(at 0 1.397 180)
			(size 0.889 0.9906)
			(layers "B.Cu" "B.Mask" "B.Paste")
			(net "GND")
		)
		(zone
			(layer "B.Cu")
			(hatch none 0.5)
			(connect_pads
				(clearance 0)
			)
			(min_thickness 0.25)
			(keepout
				(tracks allowed)
				(vias not_allowed)
				(pads allowed)
				(copperpour not_allowed)
				(footprints allowed)
			)
			(placement
				(enabled no)
				(sheetname "")
			)
			(fill
				(thermal_gap 0.5)
				(thermal_bridge_width 0.5)
				(island_removal_mode 0)
			)
			(polygon
				(pts
					(xy 82.903568 -144.5133) (xy 83.411568 -144.5133) (xy 83.411568 -145.5039) (xy 82.903568 -145.5039)
				)
			)
		)
		(zone
			(layer "B.Cu")
			(hatch none 0.5)
			(connect_pads
				(clearance 0)
			)
			(min_thickness 0.25)
			(keepout
				(tracks not_allowed)
				(vias allowed)
				(pads allowed)
				(copperpour not_allowed)
				(footprints allowed)
			)
			(placement
				(enabled no)
				(sheetname "")
			)
			(fill
				(thermal_gap 0.5)
				(thermal_bridge_width 0.5)
				(island_removal_mode 0)
			)
			(polygon
				(pts
					(xy 82.903568 -144.5133) (xy 83.411568 -144.5133) (xy 83.411568 -145.5039) (xy 82.903568 -145.5039)
				)
			)
		)
	)
)
